# Barreleye-G2_Tri-mode Expander-DVT-X01-SKU-BOM-X07-20171222_Final.xls.xlsx — Component Qual Tracker (bom)
|  |  |  |  |  |  |  |  | Part to be included on following build: |  |  |  |  |  |
| Item No. | Part Group | Single/Sole/Multi | Item Description | ODM P/N | Customer PN | Vendor | Vendor P/N | X00 Build | X01 Build | X02 Build | Qual Build | Qualification Target Date | Qualification Complete Date |
|  | VR Controllers |  |  |  |  | Vendor #1 |  |  |  |  |  |  |  |
|  |  |  |  |  |  | Vendor #2 |  |  |  |  |  |  |  |
|  | FETS |  |  |  |  | Vendor #1 |  |  |  |  |  |  |  |
|  |  |  |  |  |  | Vendor #2 |  |  |  |  |  |  |  |
|  | INDUCTORS |  |  |  |  | Vendor #1 |  |  |  |  |  |  |  |
|  |  |  |  |  |  | Vendor #2 |  |  |  |  |  |  |  |
|  | VREG CAPS |  |  |  |  | Vendor #1 |  |  |  |  |  |  |  |
|  |  |  |  |  |  | Vendor #2 |  |  |  |  |  |  |  |
|  | CRYSTALS |  |  |  |  | Vendor #1 |  |  |  |  |  |  |  |
|  |  |  |  |  |  | Vendor #2 |  |  |  |  |  |  |  |
|  | CONNECTORS |  |  |  |  | Vendor #1 |  |  |  |  |  |  |  |
|  |  |  |  |  |  | Vendor #2 |  |  |  |  |  |  |  |
|  | IC'S |  |  |  |  | Vendor #1 |  |  |  |  |  |  |  |
|  |  |  |  |  |  | Vendor #2 |  |  |  |  |  |  |  |
|  | MISC. |  |  |  |  | Vendor #1 |  |  |  |  |  |  |  |
|  | (HEATSINKS) |  |  |  |  | Vendor #2 |  |  |  |  |  |  |  |
